FILE_TYPE = CONNECTIVITY;
{Allegro Design Entry HDL 17.2-2016 S081 (4005846) 1/11/2022}
"PAGE_NUMBER" = 58;
0"NC";
1"GND\g";
2"GND\g";
3"GND\g";
4"GND\g";
5"GND\g";
6"GND\g";
7"GND\g";
8"GND\g";
9"GND\g";
10"GND\g";
11"GND\g";
12"GND\g";
%"GENOA_SP5"
"28","(-8575,3425)","0","pure_quanta","I1";
;
LOCATION"U26"
$SEC"28"
CDS_SEC"28"
PART_TYPE"SMLF"
MATERIAL"IO"
VALUE"SOCKET6096_13568-001"
PART_NUMBER"DGA^6000030"
CDS_LIB"pure_quanta"
CDS_LMAN_SYM_OUTLINE"-400,3050,400,-3050"
NEEDS_NO_SIZE"TRUE";
"VSS_H34"
$PN"H34"2;
"VSS_H31"
$PN"H31"2;
"VSS_H28"
$PN"H28"2;
"VSS_H25"
$PN"H25"2;
"VSS_H22"
$PN"H22"2;
"VSS_H17"
$PN"H17"2;
"VSS_H15"
$PN"H15"2;
"VSS_H10"
$PN"H10"2;
"VSS_H8"
$PN"H8"2;
"VSS_H3"
$PN"H3"2;
"VSS_G75"
$PN"G75"2;
"VSS_G72"
$PN"G72"2;
"VSS_G70"
$PN"G70"2;
"VSS_G68"
$PN"G68"2;
"VSS_G65"
$PN"G65"2;
"VSS_G63"
$PN"G63"2;
"VSS_G61"
$PN"G61"2;
"VSS_G58"
$PN"G58"2;
"VSS_G56"
$PN"G56"2;
"VSS_G54"
$PN"G54"2;
"VSS_G51"
$PN"G51"2;
"VSS_G48"
$PN"G48"2;
"VSS_G45"
$PN"G45"2;
"VSS_G42"
$PN"G42"2;
"VSS_G34"
$PN"G34"2;
"VSS_G31"
$PN"G31"2;
"VSS_G28"
$PN"G28"2;
"VSS_G25"
$PN"G25"2;
"VSS_G22"
$PN"G22"2;
"VSS_G20"
$PN"G20"2;
"VSS_G18"
$PN"G18"2;
"VSS_G15"
$PN"G15"2;
"VSS_G13"
$PN"G13"2;
"VSS_G11"
$PN"G11"2;
"VSS_G8"
$PN"G8"2;
"VSS_G6"
$PN"G6"2;
"VSS_G4"
$PN"G4"2;
"VSS_G1"
$PN"G1"2;
"VSS_F73"
$PN"F73"2;
"VSS_F71"
$PN"F71"2;
"VSS_F68"
$PN"F68"2;
"VSS_F66"
$PN"F66"2;
"VSS_F64"
$PN"F64"2;
"VSS_F61"
$PN"F61"2;
"VSS_F59"
$PN"F59"2;
"VSS_F57"
$PN"F57"2;
"VSS_F53"
$PN"F53"2;
"VSS_F52"
$PN"F52"2;
"VSS_F50"
$PN"F50"2;
"VSS_F49"
$PN"F49"2;
"VSS_F47"
$PN"F47"2;
"VSS_F46"
$PN"F46"2;
"VSS_F44"
$PN"F44"2;
"VSS_F43"
$PN"F43"2;
"VSS_F41"
$PN"F41"2;
"VSS_F40"
$PN"F40"2;
"VSS_F39"
$PN"F39"2;
"VSS_F37"
$PN"F37"2;
"VSS_F36"
$PN"F36"2;
"VSS_F35"
$PN"F35"2;
"VSS_F33"
$PN"F33"2;
"VSS_F32"
$PN"F32"2;
"VSS_F30"
$PN"F30"2;
"VSS_F29"
$PN"F29"2;
"VSS_F27"
$PN"F27"2;
"VSS_F26"
$PN"F26"2;
"VSS_F24"
$PN"F24"2;
"VSS_F23"
$PN"F23"2;
"VSS_F19"
$PN"F19"2;
"VSS_F17"
$PN"F17"2;
"VSS_F15"
$PN"F15"2;
"VSS_F12"
$PN"F12"2;
"VSS_F10"
$PN"F10"2;
"VSS_F8"
$PN"F8"2;
"VSS_F5"
$PN"F5"2;
"VSS_F3"
$PN"F3"2;
"VSS_E75"
$PN"E75"2;
"VSS_E73"
$PN"E73"2;
"VSS_E72"
$PN"E72"2;
"VSS_E70"
$PN"E70"2;
"VSS_E69"
$PN"E69"2;
"VSS_E68"
$PN"E68"2;
"VSS_E66"
$PN"E66"2;
"VSS_E65"
$PN"E65"2;
"VSS_E63"
$PN"E63"2;
"VSS_E62"
$PN"E62"2;
"VSS_E61"
$PN"E61"2;
"VSS_E59"
$PN"E59"2;
"VSS_E58"
$PN"E58"2;
"VSS_E56"
$PN"E56"2;
"VSS_E55"
$PN"E55"2;
"VSS_E53"
$PN"E53"2;
"VSS_E52"
$PN"E52"2;
"VSS_E21"
$PN"E21"2;
"VSS_E20"
$PN"E20"2;
"VSS_E18"
$PN"E18"2;
"VSS_E17"
$PN"E17"2;
"VSS_E15"
$PN"E15"2;
"VSS_E14"
$PN"E14"2;
"VSS_E13"
$PN"E13"2;
"VSS_E10"
$PN"E10"2;
"VSS_E8"
$PN"E8"1;
"VSS_E7"
$PN"E7"1;
"VSS_E6"
$PN"E6"1;
"VSS_E3"
$PN"E3"1;
"VSS_E1"
$PN"E1"1;
"VSS_D74"
$PN"D74"1;
"VSS_D73"
$PN"D73"1;
"VSS_D71"
$PN"D71"1;
"VSS_D70"
$PN"D70"1;
"VSS_D67"
$PN"D67"1;
"VSS_D66"
$PN"D66"1;
"VSS_D64"
$PN"D64"1;
"VSS_D63"
$PN"D63"1;
"VSS_D61"
$PN"D61"1;
"VSS_D60"
$PN"D60"1;
"VSS_D59"
$PN"D59"1;
"VSS_D57"
$PN"D57"1;
"VSS_D54"
$PN"D54"1;
"VSS_D53"
$PN"D53"1;
"VSS_D52"
$PN"D52"1;
"VSS_D51"
$PN"D51"1;
"VSS_D50"
$PN"D50"1;
"VSS_D49"
$PN"D49"1;
"VSS_D48"
$PN"D48"1;
"VSS_D47"
$PN"D47"1;
"VSS_D46"
$PN"D46"1;
"VSS_D45"
$PN"D45"1;
"VSS_D44"
$PN"D44"1;
"VSS_D43"
$PN"D43"1;
"VSS_D42"
$PN"D42"1;
"VSS_D41"
$PN"D41"1;
"VSS_D40"
$PN"D40"1;
"VSS_D39"
$PN"D39"1;
"VSS_D37"
$PN"D37"1;
"VSS_D35"
$PN"D35"1;
"VSS_D31"
$PN"D31"1;
"VSS_D30"
$PN"D30"1;
"VSS_D29"
$PN"D29"1;
"VSS_D28"
$PN"D28"1;
"VSS_D27"
$PN"D27"1;
"VSS_D26"
$PN"D26"1;
"VSS_D25"
$PN"D25"1;
"VSS_D24"
$PN"D24"1;
"VSS_D21"
$PN"D21"1;
"VSS_D20"
$PN"D20"1;
"VSS_D19"
$PN"D19"1;
"VSS_D17"
$PN"D17"1;
"VSS_D16"
$PN"D16"1;
"VSS_D13"
$PN"D13"1;
"VSS_D12"
$PN"D12"1;
"VSS_D10"
$PN"D10"1;
"VSS_D9"
$PN"D9"1;
"VSS_D6"
$PN"D6"1;
"VSS_D5"
$PN"D5"1;
"VSS_D3"
$PN"D3"1;
"VSS_D2"
$PN"D2"1;
"VSS_C75"
$PN"C75"1;
"VSS_C73"
$PN"C73"1;
"VSS_C71"
$PN"C71"1;
"VSS_C69"
$PN"C69"1;
"VSS_C67"
$PN"C67"1;
"VSS_C64"
$PN"C64"1;
"VSS_C61"
$PN"C61"1;
"VSS_C57"
$PN"C57"1;
"VSS_C56"
$PN"C56"1;
"VSS_C55"
$PN"C55"1;
"VSS_C52"
$PN"C52"1;
"VSS_C49"
$PN"C49"1;
"VSS_C46"
$PN"C46"1;
"VSS_C43"
$PN"C43"1;
"VSS_C40"
$PN"C40"1;
"VSS_C36"
$PN"C36"1;
"VSS_C30"
$PN"C30"1;
"VSS_C27"
$PN"C27"1;
"VSS_C24"
$PN"C24"1;
"VSS_C21"
$PN"C21"1;
"VSS_C15"
$PN"C15"1;
"VSS_C13"
$PN"C13"1;
"VSS_C11"
$PN"C11"1;
"VSS_C10"
$PN"C10"1;
"VSS_C8"
$PN"C8"1;
"VSS_C5"
$PN"C5"1;
"VSS_C1"
$PN"C1"1;
"VSS_B70"
$PN"B70"1;
"VSS_B68"
$PN"B68"1;
"VSS_B65"
$PN"B65"1;
"VSS_B62"
$PN"B62"1;
"VSS_B59"
$PN"B59"1;
"VSS_B55"
$PN"B55"1;
"VSS_B52"
$PN"B52"1;
"VSS_B49"
$PN"B49"1;
"VSS_B46"
$PN"B46"1;
"VSS_B43"
$PN"B43"1;
"VSS_B39"
$PN"B39"1;
"VSS_B37"
$PN"B37"1;
"VSS_B33"
$PN"B33"1;
"VSS_B30"
$PN"B30"1;
"VSS_B27"
$PN"B27"1;
"VSS_B24"
$PN"B24"1;
"VSS_B18"
$PN"B18"1;
"VSS_B13"
$PN"B13"1;
"VSS_B11"
$PN"B11"1;
"VSS_B10"
$PN"B10"1;
"VSS_B8"
$PN"B8"1;
"VSS_B7"
$PN"B7"1;
"VSS_A73"
$PN"A73"1;
"VSS_A72"
$PN"A72"1;
"VSS_A67"
$PN"A67"1;
"VSS_A61"
$PN"A61"1;
"VSS_A53"
$PN"A53"1;
"VSS_A49"
$PN"A49"1;
"VSS_A47"
$PN"A47"1;
"VSS_A44"
$PN"A44"1;
"VSS_A43"
$PN"A43"1;
"VSS_A27"
$PN"A27"1;
"VSS_A21"
$PN"A21"1;
"VSS_A15"
$PN"A15"1;
"VSS_A9"
$PN"A9"1;
"VSS_A3"
$PN"A3"1;
"VSS_J13"
$PN"J13"2;
"VSS_J11"
$PN"J11"2;
"VSS_J8"
$PN"J8"2;
"VSS_J6"
$PN"J6"2;
"VSS_J4"
$PN"J4"2;
"VSS_J1"
$PN"J1"2;
"VSS_H73"
$PN"H73"2;
"VSS_H68"
$PN"H68"2;
"VSS_H66"
$PN"H66"2;
"VSS_H61"
$PN"H61"2;
"VSS_H59"
$PN"H59"2;
"VSS_H54"
$PN"H54"2;
"VSS_H51"
$PN"H51"2;
"VSS_H48"
$PN"H48"2;
"VSS_H45"
$PN"H45"2;
"VSS_H42"
$PN"H42"2;
"VSS_H39"
$PN"H39"2;
"VSS_H37"
$PN"H37"2;
%"GENOA_SP5"
"30","(-5575,3475)","0","pure_quanta","I12";
;
LOCATION"U26"
$SEC"30"
CDS_SEC"30"
PART_TYPE"SMLF"
MATERIAL"IO"
VALUE"SOCKET6096_13568-001"
PART_NUMBER"DGA^6000030"
CDS_LIB"pure_quanta"
CDS_LMAN_SYM_OUTLINE"-400,3050,400,-3050"
NEEDS_NO_SIZE"TRUE";
"VSS_AB66"
$PN"AB66"6;
"VSS_AB64"
$PN"AB64"6;
"VSS_AB61"
$PN"AB61"6;
"VSS_AB59"
$PN"AB59"6;
"VSS_AB57"
$PN"AB57"6;
"VSS_AB54"
$PN"AB54"6;
"VSS_AB51"
$PN"AB51"6;
"VSS_AB48"
$PN"AB48"6;
"VSS_AB45"
$PN"AB45"6;
"VSS_AB42"
$PN"AB42"6;
"VSS_AB39"
$PN"AB39"6;
"VSS_AB37"
$PN"AB37"6;
"VSS_AB34"
$PN"AB34"6;
"VSS_AB31"
$PN"AB31"6;
"VSS_AB28"
$PN"AB28"6;
"VSS_AB25"
$PN"AB25"6;
"VSS_AB22"
$PN"AB22"6;
"VSS_AB19"
$PN"AB19"6;
"VSS_AB17"
$PN"AB17"6;
"VSS_AB15"
$PN"AB15"6;
"VSS_AB12"
$PN"AB12"6;
"VSS_AB10"
$PN"AB10"6;
"VSS_AB8"
$PN"AB8"6;
"VSS_AB5"
$PN"AB5"6;
"VSS_AB3"
$PN"AB3"6;
"VSS_AA75"
$PN"AA75"6;
"VSS_AA70"
$PN"AA70"6;
"VSS_AA68"
$PN"AA68"6;
"VSS_AA65"
$PN"AA65"6;
"VSS_AA63"
$PN"AA63"6;
"VSS_AA61"
$PN"AA61"6;
"VSS_AA58"
$PN"AA58"6;
"VSS_AA56"
$PN"AA56"6;
"VSS_AA45"
$PN"AA45"6;
"VSS_AA41"
$PN"AA41"6;
"VSS_AA40"
$PN"AA40"6;
"VSS_AA36"
$PN"AA36"6;
"VSS_AA35"
$PN"AA35"6;
"VSS_AA34"
$PN"AA34"6;
"VSS_AA31"
$PN"AA31"6;
"VSS_AA20"
$PN"AA20"6;
"VSS_AA18"
$PN"AA18"6;
"VSS_AA15"
$PN"AA15"6;
"VSS_AA13"
$PN"AA13"6;
"VSS_AA11"
$PN"AA11"6;
"VSS_AA8"
$PN"AA8"6;
"VSS_AA6"
$PN"AA6"6;
"VSS_AA4"
$PN"AA4"6;
"VSS_AA1"
$PN"AA1"6;
"VSS_Y73"
$PN"Y73"6;
"VSS_Y68"
$PN"Y68"6;
"VSS_Y66"
$PN"Y66"6;
"VSS_Y61"
$PN"Y61"6;
"VSS_Y59"
$PN"Y59"6;
"VSS_Y54"
$PN"Y54"6;
"VSS_Y53"
$PN"Y53"6;
"VSS_Y52"
$PN"Y52"6;
"VSS_Y51"
$PN"Y51"6;
"VSS_Y50"
$PN"Y50"6;
"VSS_Y49"
$PN"Y49"6;
"VSS_Y48"
$PN"Y48"6;
"VSS_Y45"
$PN"Y45"6;
"VSS_Y44"
$PN"Y44"6;
"VSS_Y43"
$PN"Y43"5;
"VSS_Y42"
$PN"Y42"5;
"VSS_Y39"
$PN"Y39"5;
"VSS_Y37"
$PN"Y37"5;
"VSS_Y34"
$PN"Y34"5;
"VSS_Y33"
$PN"Y33"5;
"VSS_Y32"
$PN"Y32"5;
"VSS_Y31"
$PN"Y31"5;
"VSS_Y28"
$PN"Y28"5;
"VSS_Y27"
$PN"Y27"5;
"VSS_Y26"
$PN"Y26"5;
"VSS_Y25"
$PN"Y25"5;
"VSS_Y24"
$PN"Y24"5;
"VSS_Y23"
$PN"Y23"5;
"VSS_Y22"
$PN"Y22"5;
"VSS_Y17"
$PN"Y17"5;
"VSS_Y15"
$PN"Y15"5;
"VSS_Y10"
$PN"Y10"5;
"VSS_Y8"
$PN"Y8"5;
"VSS_Y3"
$PN"Y3"5;
"VSS_W75"
$PN"W75"5;
"VSS_W72"
$PN"W72"5;
"VSS_W70"
$PN"W70"5;
"VSS_W68"
$PN"W68"5;
"VSS_W65"
$PN"W65"5;
"VSS_W63"
$PN"W63"5;
"VSS_W61"
$PN"W61"5;
"VSS_W58"
$PN"W58"5;
"VSS_W56"
$PN"W56"5;
"VSS_W54"
$PN"W54"5;
"VSS_W51"
$PN"W51"5;
"VSS_W48"
$PN"W48"5;
"VSS_W45"
$PN"W45"5;
"VSS_W42"
$PN"W42"5;
"VSS_W41"
$PN"W41"5;
"VSS_W40"
$PN"W40"5;
"VSS_W36"
$PN"W36"5;
"VSS_W35"
$PN"W35"5;
"VSS_W34"
$PN"W34"5;
"VSS_W28"
$PN"W28"5;
"VSS_W25"
$PN"W25"5;
"VSS_W22"
$PN"W22"5;
"VSS_W20"
$PN"W20"5;
"VSS_W18"
$PN"W18"5;
"VSS_W15"
$PN"W15"5;
"VSS_W13"
$PN"W13"5;
"VSS_W11"
$PN"W11"5;
"VSS_W8"
$PN"W8"5;
"VSS_W6"
$PN"W6"5;
"VSS_W4"
$PN"W4"5;
"VSS_W1"
$PN"W1"5;
"VSS_V73"
$PN"V73"5;
"VSS_V71"
$PN"V71"5;
"VSS_V66"
$PN"V66"5;
"VSS_V64"
$PN"V64"5;
"VSS_V61"
$PN"V61"5;
"VSS_V59"
$PN"V59"5;
"VSS_V57"
$PN"V57"5;
"VSS_V53"
$PN"V53"5;
"VSS_V52"
$PN"V52"5;
"VSS_V51"
$PN"V51"5;
"VSS_V50"
$PN"V50"5;
"VSS_V49"
$PN"V49"5;
"VSS_V48"
$PN"V48"5;
"VSS_V47"
$PN"V47"5;
"VSS_V46"
$PN"V46"5;
"VSS_V45"
$PN"V45"5;
"VSS_V44"
$PN"V44"5;
"VSS_V43"
$PN"V43"5;
"VSS_V42"
$PN"V42"5;
"VSS_V39"
$PN"V39"5;
"VSS_V37"
$PN"V37"5;
"VSS_V34"
$PN"V34"5;
"VSS_V33"
$PN"V33"5;
"VSS_V32"
$PN"V32"5;
"VSS_V31"
$PN"V31"5;
"VSS_V30"
$PN"V30"5;
"VSS_V29"
$PN"V29"5;
"VSS_V28"
$PN"V28"5;
"VSS_V26"
$PN"V26"5;
"VSS_V25"
$PN"V25"5;
"VSS_V24"
$PN"V24"5;
"VSS_V23"
$PN"V23"5;
"VSS_V19"
$PN"V19"5;
"VSS_V17"
$PN"V17"5;
"VSS_V15"
$PN"V15"5;
"VSS_V12"
$PN"V12"5;
"VSS_V10"
$PN"V10"5;
"VSS_V8"
$PN"V8"5;
"VSS_V5"
$PN"V5"5;
"VSS_V3"
$PN"V3"5;
"VSS_U75"
$PN"U75"5;
"VSS_U70"
$PN"U70"5;
"VSS_U68"
$PN"U68"5;
"VSS_U63"
$PN"U63"5;
"VSS_U61"
$PN"U61"5;
"VSS_U56"
$PN"U56"5;
"VSS_U54"
$PN"U54"5;
"VSS_U51"
$PN"U51"5;
"VSS_U48"
$PN"U48"5;
"VSS_U45"
$PN"U45"5;
"VSS_U42"
$PN"U42"5;
"VSS_U34"
$PN"U34"5;
"VSS_U31"
$PN"U31"5;
"VSS_U28"
$PN"U28"5;
"VSS_U25"
$PN"U25"5;
"VSS_U22"
$PN"U22"5;
"VSS_U20"
$PN"U20"5;
"VSS_U15"
$PN"U15"5;
"VSS_U13"
$PN"U13"5;
"VSS_U8"
$PN"U8"5;
"VSS_U6"
$PN"U6"5;
"VSS_U1"
$PN"U1"5;
"VSS_T73"
$PN"T73"5;
"VSS_T71"
$PN"T71"5;
"VSS_T68"
$PN"T68"5;
"VSS_T66"
$PN"T66"5;
"VSS_AD48"
$PN"AD48"6;
"VSS_AD47"
$PN"AD47"6;
"VSS_AD46"
$PN"AD46"6;
"VSS_AD45"
$PN"AD45"6;
"VSS_AD44"
$PN"AD44"6;
"VSS_AD43"
$PN"AD43"6;
"VSS_AD42"
$PN"AD42"6;
"VSS_AD39"
$PN"AD39"6;
"VSS_AD37"
$PN"AD37"6;
"VSS_AD34"
$PN"AD34"6;
"VSS_AD33"
$PN"AD33"6;
"VSS_AD32"
$PN"AD32"6;
"VSS_AD30"
$PN"AD30"6;
"VSS_AD29"
$PN"AD29"6;
"VSS_AD28"
$PN"AD28"6;
"VSS_AD27"
$PN"AD27"6;
"VSS_AD26"
$PN"AD26"6;
"VSS_AD25"
$PN"AD25"6;
"VSS_AD24"
$PN"AD24"6;
"VSS_AD23"
$PN"AD23"6;
"VSS_AD19"
$PN"AD19"6;
"VSS_AD17"
$PN"AD17"6;
"VSS_AD15"
$PN"AD15"6;
"VSS_AD12"
$PN"AD12"6;
"VSS_AD10"
$PN"AD10"6;
"VSS_AD8"
$PN"AD8"6;
"VSS_AD5"
$PN"AD5"6;
"VSS_AD3"
$PN"AD3"6;
"VSS_AC75"
$PN"AC75"6;
"VSS_AC70"
$PN"AC70"6;
"VSS_AC68"
$PN"AC68"6;
"VSS_AC63"
$PN"AC63"6;
"VSS_AC61"
$PN"AC61"6;
"VSS_AC56"
$PN"AC56"6;
"VSS_AC54"
$PN"AC54"6;
"VSS_AC51"
$PN"AC51"6;
"VSS_AC48"
$PN"AC48"6;
"VSS_AC45"
$PN"AC45"6;
"VSS_AC42"
$PN"AC42"6;
"VSS_AC34"
$PN"AC34"6;
"VSS_AC31"
$PN"AC31"6;
"VSS_AC28"
$PN"AC28"6;
"VSS_AC25"
$PN"AC25"6;
"VSS_AC22"
$PN"AC22"6;
"VSS_AC20"
$PN"AC20"6;
"VSS_AC15"
$PN"AC15"6;
"VSS_AC13"
$PN"AC13"6;
"VSS_AC8"
$PN"AC8"6;
"VSS_AC6"
$PN"AC6"6;
"VSS_AC1"
$PN"AC1"6;
"VSS_AB73"
$PN"AB73"6;
"VSS_AB71"
$PN"AB71"6;
"VSS_AB68"
$PN"AB68"6;
%"GENOA_SP5"
"29","(-7050,3450)","0","pure_quanta","I15";
;
LOCATION"U26"
$SEC"29"
CDS_SEC"29"
PART_TYPE"SMLF"
MATERIAL"IO"
VALUE"SOCKET6096_13568-001"
PART_NUMBER"DGA^6000030"
CDS_LIB"pure_quanta"
CDS_LMAN_SYM_OUTLINE"-400,3050,400,-3050"
NEEDS_NO_SIZE"TRUE";
"VSS_R45"
$PN"R45"4;
"VSS_R42"
$PN"R42"4;
"VSS_R41"
$PN"R41"4;
"VSS_R40"
$PN"R40"4;
"VSS_R36"
$PN"R36"4;
"VSS_R35"
$PN"R35"4;
"VSS_R34"
$PN"R34"4;
"VSS_R31"
$PN"R31"4;
"VSS_R28"
$PN"R28"4;
"VSS_R25"
$PN"R25"4;
"VSS_R22"
$PN"R22"4;
"VSS_R20"
$PN"R20"4;
"VSS_R18"
$PN"R18"4;
"VSS_R15"
$PN"R15"4;
"VSS_R13"
$PN"R13"4;
"VSS_R11"
$PN"R11"4;
"VSS_R8"
$PN"R8"4;
"VSS_R6"
$PN"R6"4;
"VSS_R4"
$PN"R4"4;
"VSS_R1"
$PN"R1"4;
"VSS_P73"
$PN"P73"4;
"VSS_P66"
$PN"P66"4;
"VSS_P61"
$PN"P61"4;
"VSS_P59"
$PN"P59"4;
"VSS_P53"
$PN"P53"4;
"VSS_P52"
$PN"P52"4;
"VSS_P51"
$PN"P51"4;
"VSS_P50"
$PN"P50"4;
"VSS_P49"
$PN"P49"4;
"VSS_P48"
$PN"P48"4;
"VSS_P47"
$PN"P47"4;
"VSS_P46"
$PN"P46"4;
"VSS_P45"
$PN"P45"4;
"VSS_P44"
$PN"P44"4;
"VSS_P43"
$PN"P43"4;
"VSS_P42"
$PN"P42"4;
"VSS_P39"
$PN"P39"4;
"VSS_P37"
$PN"P37"4;
"VSS_P34"
$PN"P34"4;
"VSS_P33"
$PN"P33"4;
"VSS_P32"
$PN"P32"4;
"VSS_P31"
$PN"P31"4;
"VSS_P30"
$PN"P30"4;
"VSS_P29"
$PN"P29"4;
"VSS_P28"
$PN"P28"4;
"VSS_P27"
$PN"P27"4;
"VSS_P26"
$PN"P26"4;
"VSS_P24"
$PN"P24"4;
"VSS_P23"
$PN"P23"4;
"VSS_P17"
$PN"P17"4;
"VSS_P15"
$PN"P15"4;
"VSS_P10"
$PN"P10"4;
"VSS_P8"
$PN"P8"4;
"VSS_P3"
$PN"P3"4;
"VSS_N75"
$PN"N75"4;
"VSS_N72"
$PN"N72"4;
"VSS_N70"
$PN"N70"4;
"VSS_N68"
$PN"N68"4;
"VSS_N65"
$PN"N65"4;
"VSS_N63"
$PN"N63"4;
"VSS_N61"
$PN"N61"4;
"VSS_N58"
$PN"N58"4;
"VSS_N56"
$PN"N56"4;
"VSS_N54"
$PN"N54"4;
"VSS_N51"
$PN"N51"4;
"VSS_N48"
$PN"N48"4;
"VSS_N45"
$PN"N45"4;
"VSS_N42"
$PN"N42"4;
"VSS_N34"
$PN"N34"4;
"VSS_N31"
$PN"N31"4;
"VSS_N28"
$PN"N28"4;
"VSS_N25"
$PN"N25"4;
"VSS_N22"
$PN"N22"4;
"VSS_N20"
$PN"N20"4;
"VSS_N18"
$PN"N18"4;
"VSS_N15"
$PN"N15"4;
"VSS_N13"
$PN"N13"4;
"VSS_N11"
$PN"N11"4;
"VSS_N8"
$PN"N8"4;
"VSS_N6"
$PN"N6"4;
"VSS_N4"
$PN"N4"4;
"VSS_N1"
$PN"N1"3;
"VSS_M73"
$PN"M73"3;
"VSS_M71"
$PN"M71"3;
"VSS_M68"
$PN"M68"3;
"VSS_M66"
$PN"M66"3;
"VSS_M64"
$PN"M64"3;
"VSS_M61"
$PN"M61"3;
"VSS_M59"
$PN"M59"3;
"VSS_M57"
$PN"M57"3;
"VSS_M54"
$PN"M54"3;
"VSS_M51"
$PN"M51"3;
"VSS_M48"
$PN"M48"3;
"VSS_M45"
$PN"M45"3;
"VSS_M42"
$PN"M42"3;
"VSS_M39"
$PN"M39"3;
"VSS_M37"
$PN"M37"3;
"VSS_M34"
$PN"M34"3;
"VSS_M31"
$PN"M31"3;
"VSS_M28"
$PN"M28"3;
"VSS_M25"
$PN"M25"3;
"VSS_M22"
$PN"M22"3;
"VSS_M19"
$PN"M19"3;
"VSS_M17"
$PN"M17"3;
"VSS_M15"
$PN"M15"3;
"VSS_M12"
$PN"M12"3;
"VSS_M10"
$PN"M10"3;
"VSS_M8"
$PN"M8"3;
"VSS_M5"
$PN"M5"3;
"VSS_M3"
$PN"M3"3;
"VSS_L75"
$PN"L75"3;
"VSS_L70"
$PN"L70"3;
"VSS_L68"
$PN"L68"3;
"VSS_L63"
$PN"L63"3;
"VSS_L61"
$PN"L61"3;
"VSS_L56"
$PN"L56"3;
"VSS_L54"
$PN"L54"3;
"VSS_L51"
$PN"L51"3;
"VSS_L48"
$PN"L48"3;
"VSS_L45"
$PN"L45"3;
"VSS_L42"
$PN"L42"3;
"VSS_L41"
$PN"L41"3;
"VSS_L40"
$PN"L40"3;
"VSS_L36"
$PN"L36"3;
"VSS_L35"
$PN"L35"3;
"VSS_L34"
$PN"L34"3;
"VSS_L31"
$PN"L31"3;
"VSS_L28"
$PN"L28"3;
"VSS_L25"
$PN"L25"3;
"VSS_L22"
$PN"L22"3;
"VSS_L20"
$PN"L20"3;
"VSS_L15"
$PN"L15"3;
"VSS_L13"
$PN"L13"3;
"VSS_L8"
$PN"L8"3;
"VSS_L6"
$PN"L6"3;
"VSS_L1"
$PN"L1"3;
"VSS_K73"
$PN"K73"3;
"VSS_K71"
$PN"K71"3;
"VSS_K68"
$PN"K68"3;
"VSS_K66"
$PN"K66"3;
"VSS_K64"
$PN"K64"3;
"VSS_K61"
$PN"K61"3;
"VSS_K57"
$PN"K57"3;
"VSS_K53"
$PN"K53"3;
"VSS_K52"
$PN"K52"3;
"VSS_K51"
$PN"K51"3;
"VSS_K50"
$PN"K50"3;
"VSS_K49"
$PN"K49"3;
"VSS_K48"
$PN"K48"3;
"VSS_K47"
$PN"K47"3;
"VSS_K46"
$PN"K46"3;
"VSS_K45"
$PN"K45"3;
"VSS_K44"
$PN"K44"3;
"VSS_K43"
$PN"K43"3;
"VSS_K42"
$PN"K42"3;
"VSS_K39"
$PN"K39"3;
"VSS_K37"
$PN"K37"3;
"VSS_K34"
$PN"K34"3;
"VSS_K33"
$PN"K33"3;
"VSS_K32"
$PN"K32"3;
"VSS_K31"
$PN"K31"3;
"VSS_K30"
$PN"K30"3;
"VSS_K29"
$PN"K29"3;
"VSS_K28"
$PN"K28"3;
"VSS_K27"
$PN"K27"3;
"VSS_K26"
$PN"K26"3;
"VSS_K25"
$PN"K25"3;
"VSS_K24"
$PN"K24"3;
"VSS_K19"
$PN"K19"3;
"VSS_K17"
$PN"K17"3;
"VSS_K15"
$PN"K15"3;
"VSS_K12"
$PN"K12"3;
"VSS_K10"
$PN"K10"3;
"VSS_K8"
$PN"K8"3;
"VSS_K5"
$PN"K5"3;
"VSS_K3"
$PN"K3"3;
"VSS_J75"
$PN"J75"3;
"VSS_J72"
$PN"J72"3;
"VSS_J70"
$PN"J70"3;
"VSS_J68"
$PN"J68"3;
"VSS_J65"
$PN"J65"3;
"VSS_J63"
$PN"J63"3;
"VSS_J61"
$PN"J61"3;
"VSS_J58"
$PN"J58"3;
"VSS_J56"
$PN"J56"3;
"VSS_J54"
$PN"J54"3;
"VSS_J51"
$PN"J51"3;
"VSS_J48"
$PN"J48"3;
"VSS_J45"
$PN"J45"3;
"VSS_J42"
$PN"J42"3;
"VSS_J34"
$PN"J34"3;
"VSS_J31"
$PN"J31"3;
"VSS_J28"
$PN"J28"3;
"VSS_J25"
$PN"J25"3;
"VSS_J22"
$PN"J22"3;
"VSS_J20"
$PN"J20"3;
"VSS_J18"
$PN"J18"3;
"VSS_J15"
$PN"J15"3;
"VSS_T64"
$PN"T64"4;
"VSS_T61"
$PN"T61"4;
"VSS_T59"
$PN"T59"4;
"VSS_T57"
$PN"T57"4;
"VSS_T54"
$PN"T54"4;
"VSS_T51"
$PN"T51"4;
"VSS_T48"
$PN"T48"4;
"VSS_T45"
$PN"T45"4;
"VSS_T42"
$PN"T42"4;
"VSS_T39"
$PN"T39"4;
"VSS_T37"
$PN"T37"4;
"VSS_T34"
$PN"T34"4;
"VSS_T31"
$PN"T31"4;
"VSS_T28"
$PN"T28"4;
"VSS_T25"
$PN"T25"4;
"VSS_T22"
$PN"T22"4;
"VSS_T19"
$PN"T19"4;
"VSS_T17"
$PN"T17"4;
"VSS_T15"
$PN"T15"4;
"VSS_T12"
$PN"T12"4;
"VSS_T10"
$PN"T10"4;
"VSS_T8"
$PN"T8"4;
"VSS_T5"
$PN"T5"4;
"VSS_T3"
$PN"T3"4;
"VSS_R75"
$PN"R75"4;
"VSS_R72"
$PN"R72"4;
"VSS_R70"
$PN"R70"4;
"VSS_R68"
$PN"R68"4;
"VSS_R65"
$PN"R65"4;
"VSS_R63"
$PN"R63"4;
"VSS_R61"
$PN"R61"4;
"VSS_R58"
$PN"R58"4;
"VSS_R56"
$PN"R56"4;
"VSS_R54"
$PN"R54"4;
"VSS_R51"
$PN"R51"4;
"VSS_R48"
$PN"R48"4;
%"UNIVERSAL_GND"
"1","(-9250,375)","0","pure_quanta_power","I18";
;
CDS_LIB"pure_quanta_power"
HDL_POWER"GND";
"A"1;
%"UNIVERSAL_GND"
"1","(-7900,400)","0","pure_quanta_power","I19";
;
CDS_LIB"pure_quanta_power"
HDL_POWER"GND";
"A"2;
%"UNIVERSAL_GND"
"1","(-7725,400)","0","pure_quanta_power","I20";
;
CDS_LIB"pure_quanta_power"
HDL_POWER"GND";
"A"3;
%"UNIVERSAL_GND"
"1","(-6375,425)","0","pure_quanta_power","I21";
;
CDS_LIB"pure_quanta_power"
HDL_POWER"GND";
"A"4;
%"UNIVERSAL_GND"
"1","(-6250,425)","0","pure_quanta_power","I22";
;
CDS_LIB"pure_quanta_power"
HDL_POWER"GND";
"A"5;
%"UNIVERSAL_GND"
"1","(-4900,500)","0","pure_quanta_power","I23";
;
CDS_LIB"pure_quanta_power"
HDL_POWER"GND";
"A"6;
%"UNIVERSAL_GND"
"1","(-4750,500)","0","pure_quanta_power","I24";
;
CDS_LIB"pure_quanta_power"
HDL_POWER"GND";
"A"7;
%"UNIVERSAL_GND"
"1","(-3400,525)","0","pure_quanta_power","I25";
;
CDS_LIB"pure_quanta_power"
HDL_POWER"GND";
"A"8;
%"UNIVERSAL_GND"
"1","(-3250,450)","0","pure_quanta_power","I26";
;
CDS_LIB"pure_quanta_power"
HDL_POWER"GND";
"A"9;
%"UNIVERSAL_GND"
"1","(-1925,475)","0","pure_quanta_power","I27";
;
CDS_LIB"pure_quanta_power"
HDL_POWER"GND";
"A"10;
%"UNIVERSAL_GND"
"1","(-1625,450)","0","pure_quanta_power","I28";
;
CDS_LIB"pure_quanta_power"
HDL_POWER"GND";
"A"11;
%"UNIVERSAL_GND"
"1","(-300,475)","0","pure_quanta_power","I29";
;
CDS_LIB"pure_quanta_power"
HDL_POWER"GND";
"A"12;
%"GENOA_SP5"
"33","(-975,3500)","0","pure_quanta","I3";
;
LOCATION"U26"
$SEC"33"
CDS_SEC"33"
PART_TYPE"SMLF"
MATERIAL"IO"
VALUE"SOCKET6096_13568-001"
PART_NUMBER"DGA^6000030"
CDS_LIB"pure_quanta"
CDS_LMAN_SYM_OUTLINE"-400,3050,400,-3050"
NEEDS_NO_SIZE"TRUE";
"VSS_BL24"
$PN"BL24"12;
"VSS_BL22"
$PN"BL22"12;
"VSS_BL20"
$PN"BL20"12;
"VSS_BL18"
$PN"BL18"12;
"VSS_BL15"
$PN"BL15"12;
"VSS_BL13"
$PN"BL13"12;
"VSS_BL11"
$PN"BL11"12;
"VSS_BL8"
$PN"BL8"12;
"VSS_BL6"
$PN"BL6"12;
"VSS_BL4"
$PN"BL4"12;
"VSS_BL1"
$PN"BL1"12;
"VSS_BK73"
$PN"BK73"12;
"VSS_BK71"
$PN"BK71"12;
"VSS_BK68"
$PN"BK68"12;
"VSS_BK66"
$PN"BK66"12;
"VSS_BK64"
$PN"BK64"12;
"VSS_BK61"
$PN"BK61"12;
"VSS_BK59"
$PN"BK59"12;
"VSS_BK57"
$PN"BK57"12;
"VSS_BK54"
$PN"BK54"12;
"VSS_BK52"
$PN"BK52"12;
"VSS_BK50"
$PN"BK50"12;
"VSS_BK48"
$PN"BK48"12;
"VSS_BK27"
$PN"BK27"12;
"VSS_BK25"
$PN"BK25"12;
"VSS_BK23"
$PN"BK23"12;
"VSS_BK19"
$PN"BK19"12;
"VSS_BK17"
$PN"BK17"12;
"VSS_BK15"
$PN"BK15"12;
"VSS_BK12"
$PN"BK12"12;
"VSS_BK10"
$PN"BK10"12;
"VSS_BK8"
$PN"BK8"12;
"VSS_BK5"
$PN"BK5"12;
"VSS_BK3"
$PN"BK3"12;
"VSS_BJ75"
$PN"BJ75"12;
"VSS_BJ70"
$PN"BJ70"12;
"VSS_BJ68"
$PN"BJ68"12;
"VSS_BJ63"
$PN"BJ63"12;
"VSS_BJ61"
$PN"BJ61"12;
"VSS_BJ56"
$PN"BJ56"12;
"VSS_BJ53"
$PN"BJ53"12;
"VSS_BJ51"
$PN"BJ51"12;
"VSS_BJ49"
$PN"BJ49"12;
"VSS_BJ28"
$PN"BJ28"12;
"VSS_BJ26"
$PN"BJ26"12;
"VSS_BJ24"
$PN"BJ24"12;
"VSS_BJ22"
$PN"BJ22"12;
"VSS_BJ20"
$PN"BJ20"12;
"VSS_BJ15"
$PN"BJ15"12;
"VSS_BJ13"
$PN"BJ13"12;
"VSS_BJ8"
$PN"BJ8"12;
"VSS_BJ6"
$PN"BJ6"12;
"VSS_BJ1"
$PN"BJ1"12;
"VSS_BH73"
$PN"BH73"12;
"VSS_BH71"
$PN"BH71"12;
"VSS_BH68"
$PN"BH68"12;
"VSS_BH66"
$PN"BH66"12;
"VSS_BH64"
$PN"BH64"12;
"VSS_BH61"
$PN"BH61"12;
"VSS_BH59"
$PN"BH59"12;
"VSS_BH57"
$PN"BH57"12;
"VSS_BH54"
$PN"BH54"12;
"VSS_BH52"
$PN"BH52"12;
"VSS_BH50"
$PN"BH50"12;
"VSS_BH49"
$PN"BH49"12;
"VSS_BH28"
$PN"BH28"12;
"VSS_BH26"
$PN"BH26"12;
"VSS_BH24"
$PN"BH24"12;
"VSS_BH22"
$PN"BH22"12;
"VSS_BH19"
$PN"BH19"12;
"VSS_BH17"
$PN"BH17"12;
"VSS_BH15"
$PN"BH15"12;
"VSS_BH12"
$PN"BH12"12;
"VSS_BH10"
$PN"BH10"12;
"VSS_BH8"
$PN"BH8"12;
"VSS_BH5"
$PN"BH5"12;
"VSS_BH3"
$PN"BH3"12;
"VSS_BG75"
$PN"BG75"12;
"VSS_BG72"
$PN"BG72"12;
"VSS_BG70"
$PN"BG70"12;
"VSS_BG68"
$PN"BG68"12;
"VSS_BG65"
$PN"BG65"12;
"VSS_BG63"
$PN"BG63"12;
"VSS_BG61"
$PN"BG61"12;
"VSS_BG58"
$PN"BG58"12;
"VSS_BG56"
$PN"BG56"12;
"VSS_BG53"
$PN"BG53"12;
"VSS_BG51"
$PN"BG51"12;
"VSS_BG49"
$PN"BG49"12;
"VSS_BG27"
$PN"BG27"12;
"VSS_BG25"
$PN"BG25"12;
"VSS_BG23"
$PN"BG23"12;
"VSS_BG20"
$PN"BG20"12;
"VSS_BG18"
$PN"BG18"12;
"VSS_BG15"
$PN"BG15"12;
"VSS_BG13"
$PN"BG13"12;
"VSS_BG11"
$PN"BG11"12;
"VSS_BG8"
$PN"BG8"12;
"VSS_BG6"
$PN"BG6"12;
"VSS_BG4"
$PN"BG4"12;
"VSS_BG1"
$PN"BG1"12;
"VSS_BF73"
$PN"BF73"12;
"VSS_BF68"
$PN"BF68"12;
"VSS_BF66"
$PN"BF66"12;
"VSS_BF61"
$PN"BF61"12;
"VSS_BF59"
$PN"BF59"12;
"VSS_BF54"
$PN"BF54"12;
"VSS_BF52"
$PN"BF52"12;
"VSS_BF50"
$PN"BF50"12;
"VSS_BF49"
$PN"BF49"12;
"VSS_BF28"
$PN"BF28"12;
"VSS_BF26"
$PN"BF26"12;
"VSS_BF24"
$PN"BF24"12;
"VSS_BF22"
$PN"BF22"12;
"VSS_BF19"
$PN"BF19"12;
"VSS_BF17"
$PN"BF17"12;
"VSS_BF15"
$PN"BF15"12;
"VSS_BF12"
$PN"BF12"12;
"VSS_BF10"
$PN"BF10"12;
"VSS_BF8"
$PN"BF8"11;
"VSS_BF5"
$PN"BF5"11;
"VSS_BF3"
$PN"BF3"11;
"VSS_BD73"
$PN"BD73"11;
"VSS_BD71"
$PN"BD71"11;
"VSS_BD68"
$PN"BD68"11;
"VSS_BD66"
$PN"BD66"11;
"VSS_BD64"
$PN"BD64"11;
"VSS_BD61"
$PN"BD61"11;
"VSS_BD59"
$PN"BD59"11;
"VSS_BD57"
$PN"BD57"11;
"VSS_BD53"
$PN"BD53"11;
"VSS_BD51"
$PN"BD51"11;
"VSS_BD49"
$PN"BD49"11;
"VSS_BD27"
$PN"BD27"11;
"VSS_BD25"
$PN"BD25"11;
"VSS_BD23"
$PN"BD23"11;
"VSS_BD17"
$PN"BD17"11;
"VSS_BD15"
$PN"BD15"11;
"VSS_BD10"
$PN"BD10"11;
"VSS_BD8"
$PN"BD8"11;
"VSS_BD3"
$PN"BD3"11;
"VSS_BC75"
$PN"BC75"11;
"VSS_BC72"
$PN"BC72"11;
"VSS_BC70"
$PN"BC70"11;
"VSS_BC68"
$PN"BC68"11;
"VSS_BC65"
$PN"BC65"11;
"VSS_BC63"
$PN"BC63"11;
"VSS_BC61"
$PN"BC61"11;
"VSS_BC58"
$PN"BC58"11;
"VSS_BC56"
$PN"BC56"11;
"VSS_BC53"
$PN"BC53"11;
"VSS_BC51"
$PN"BC51"11;
"VSS_BC50"
$PN"BC50"11;
"VSS_BC49"
$PN"BC49"11;
"VSS_BC28"
$PN"BC28"11;
"VSS_BC26"
$PN"BC26"11;
"VSS_BC24"
$PN"BC24"11;
"VSS_BC22"
$PN"BC22"11;
"VSS_BC20"
$PN"BC20"11;
"VSS_BC18"
$PN"BC18"11;
"VSS_BC15"
$PN"BC15"11;
"VSS_BC13"
$PN"BC13"11;
"VSS_BC11"
$PN"BC11"11;
"VSS_BC8"
$PN"BC8"11;
"VSS_BC6"
$PN"BC6"11;
"VSS_BC4"
$PN"BC4"11;
"VSS_BC1"
$PN"BC1"11;
"VSS_BB73"
$PN"BB73"11;
"VSS_BB71"
$PN"BB71"11;
"VSS_BB68"
$PN"BB68"11;
"VSS_BB66"
$PN"BB66"11;
"VSS_BB64"
$PN"BB64"11;
"VSS_BB61"
$PN"BB61"11;
"VSS_BB59"
$PN"BB59"11;
"VSS_BB57"
$PN"BB57"11;
"VSS_BB54"
$PN"BB54"11;
"VSS_BB52"
$PN"BB52"11;
"VSS_BB50"
$PN"BB50"11;
"VSS_BB48"
$PN"BB48"11;
"VSS_BB27"
$PN"BB27"11;
"VSS_BB25"
$PN"BB25"11;
"VSS_BB23"
$PN"BB23"11;
"VSS_BB19"
$PN"BB19"11;
"VSS_BB17"
$PN"BB17"11;
"VSS_BB15"
$PN"BB15"11;
"VSS_BB12"
$PN"BB12"11;
"VSS_BB10"
$PN"BB10"11;
"VSS_BB8"
$PN"BB8"11;
"VSS_BB5"
$PN"BB5"11;
"VSS_BB3"
$PN"BB3"11;
"VSS_BA75"
$PN"BA75"11;
"VSS_BA70"
$PN"BA70"11;
"VSS_BA68"
$PN"BA68"11;
"VSS_BA63"
$PN"BA63"11;
"VSS_BA61"
$PN"BA61"11;
"VSS_BA56"
$PN"BA56"11;
"VSS_BA53"
$PN"BA53"11;
"VSS_BA51"
$PN"BA51"11;
"VSS_BA49"
$PN"BA49"11;
"VSS_BA28"
$PN"BA28"11;
"VSS_BA26"
$PN"BA26"11;
"VSS_BA24"
$PN"BA24"11;
"VSS_BA22"
$PN"BA22"11;
"VSS_BA20"
$PN"BA20"11;
"VSS_BA15"
$PN"BA15"11;
"VSS_BA13"
$PN"BA13"11;
"VSS_BA8"
$PN"BA8"11;
"VSS_BA6"
$PN"BA6"11;
"VSS_BA1"
$PN"BA1"11;
"VSS_AY73"
$PN"AY73"11;
"VSS_AY71"
$PN"AY71"11;
"VSS_AY68"
$PN"AY68"11;
"VSS_AY66"
$PN"AY66"11;
"VSS_AY64"
$PN"AY64"11;
"VSS_AY61"
$PN"AY61"11;
"VSS_AY59"
$PN"AY59"11;
"VSS_AY57"
$PN"AY57"11;
"VSS_AY54"
$PN"AY54"11;
"VSS_AY52"
$PN"AY52"11;
"VSS_AY50"
$PN"AY50"11;
"VSS_AY48"
$PN"AY48"11;
"VSS_AY27"
$PN"AY27"11;
"VSS_AY25"
$PN"AY25"11;
"VSS_AY23"
$PN"AY23"11;
"VSS_AY19"
$PN"AY19"11;
"VSS_AY17"
$PN"AY17"11;
"VSS_AY15"
$PN"AY15"11;
"VSS_AY12"
$PN"AY12"11;
"VSS_AY10"
$PN"AY10"11;
"VSS_AY8"
$PN"AY8"11;
"VSS_AY5"
$PN"AY5"11;
"VSS_AY3"
$PN"AY3"11;
"VSS_AW75"
$PN"AW75"11;
"VSS_AW72"
$PN"AW72"11;
"VSS_AW70"
$PN"AW70"11;
"VSS_AW68"
$PN"AW68"11;
"VSS_AW65"
$PN"AW65"11;
"VSS_AW63"
$PN"AW63"11;
%"GENOA_SP5"
"32","(-2600,3500)","0","pure_quanta","I6";
;
LOCATION"U26"
$SEC"32"
CDS_SEC"32"
PART_TYPE"SMLF"
MATERIAL"IO"
VALUE"SOCKET6096_13568-001"
PART_NUMBER"DGA^6000030"
CDS_LIB"pure_quanta"
CDS_LMAN_SYM_OUTLINE"-400,3050,400,-3050"
NEEDS_NO_SIZE"TRUE";
"VSS_AW61"
$PN"AW61"10;
"VSS_AW58"
$PN"AW58"10;
"VSS_AW56"
$PN"AW56"10;
"VSS_AW53"
$PN"AW53"10;
"VSS_AW51"
$PN"AW51"10;
"VSS_AW49"
$PN"AW49"10;
"VSS_AW28"
$PN"AW28"10;
"VSS_AW26"
$PN"AW26"10;
"VSS_AW24"
$PN"AW24"10;
"VSS_AW22"
$PN"AW22"10;
"VSS_AW20"
$PN"AW20"10;
"VSS_AW18"
$PN"AW18"10;
"VSS_AW15"
$PN"AW15"10;
"VSS_AW13"
$PN"AW13"10;
"VSS_AW11"
$PN"AW11"10;
"VSS_AW8"
$PN"AW8"10;
"VSS_AW6"
$PN"AW6"10;
"VSS_AW4"
$PN"AW4"10;
"VSS_AW1"
$PN"AW1"10;
"VSS_AV73"
$PN"AV73"10;
"VSS_AV68"
$PN"AV68"10;
"VSS_AV66"
$PN"AV66"10;
"VSS_AV61"
$PN"AV61"10;
"VSS_AV59"
$PN"AV59"10;
"VSS_AV54"
$PN"AV54"10;
"VSS_AV52"
$PN"AV52"10;
"VSS_AV50"
$PN"AV50"10;
"VSS_AV48"
$PN"AV48"10;
"VSS_AV46"
$PN"AV46"10;
"VSS_AV44"
$PN"AV44"10;
"VSS_AV42"
$PN"AV42"10;
"VSS_AV40"
$PN"AV40"10;
"VSS_AV37"
$PN"AV37"10;
"VSS_AV35"
$PN"AV35"10;
"VSS_AV33"
$PN"AV33"10;
"VSS_AV31"
$PN"AV31"10;
"VSS_AV29"
$PN"AV29"10;
"VSS_AV27"
$PN"AV27"10;
"VSS_AV25"
$PN"AV25"10;
"VSS_AV23"
$PN"AV23"10;
"VSS_AV17"
$PN"AV17"10;
"VSS_AV15"
$PN"AV15"10;
"VSS_AV10"
$PN"AV10"10;
"VSS_AV8"
$PN"AV8"10;
"VSS_AV3"
$PN"AV3"10;
"VSS_AU75"
$PN"AU75"10;
"VSS_AU73"
$PN"AU73"10;
"VSS_AU72"
$PN"AU72"10;
"VSS_AU70"
$PN"AU70"10;
"VSS_AU68"
$PN"AU68"10;
"VSS_AU65"
$PN"AU65"10;
"VSS_AU63"
$PN"AU63"10;
"VSS_AU61"
$PN"AU61"10;
"VSS_AU58"
$PN"AU58"10;
"VSS_AU56"
$PN"AU56"10;
"VSS_AU53"
$PN"AU53"10;
"VSS_AU51"
$PN"AU51"10;
"VSS_AU49"
$PN"AU49"10;
"VSS_AU47"
$PN"AU47"10;
"VSS_AU45"
$PN"AU45"10;
"VSS_AU43"
$PN"AU43"10;
"VSS_AU41"
$PN"AU41"10;
"VSS_AU36"
$PN"AU36"10;
"VSS_AU34"
$PN"AU34"10;
"VSS_AU32"
$PN"AU32"10;
"VSS_AU30"
$PN"AU30"10;
"VSS_AU28"
$PN"AU28"10;
"VSS_AU26"
$PN"AU26"10;
"VSS_AU24"
$PN"AU24"10;
"VSS_AU22"
$PN"AU22"10;
"VSS_AU20"
$PN"AU20"10;
"VSS_AU18"
$PN"AU18"10;
"VSS_AU15"
$PN"AU15"10;
"VSS_AU13"
$PN"AU13"10;
"VSS_AU11"
$PN"AU11"10;
"VSS_AU8"
$PN"AU8"10;
"VSS_AU6"
$PN"AU6"10;
"VSS_AU4"
$PN"AU4"10;
"VSS_AU3"
$PN"AU3"10;
"VSS_AU1"
$PN"AU1"10;
"VSS_AT73"
$PN"AT73"10;
"VSS_AT72"
$PN"AT72"10;
"VSS_AT71"
$PN"AT71"10;
"VSS_AT70"
$PN"AT70"10;
"VSS_AT68"
$PN"AT68"10;
"VSS_AT67"
$PN"AT67"10;
"VSS_AT66"
$PN"AT66"10;
"VSS_AT64"
$PN"AT64"10;
"VSS_AT63"
$PN"AT63"10;
"VSS_AT61"
$PN"AT61"10;
"VSS_AT60"
$PN"AT60"10;
"VSS_AT59"
$PN"AT59"10;
"VSS_AT57"
$PN"AT57"10;
"VSS_AT56"
$PN"AT56"10;
"VSS_AT54"
$PN"AT54"10;
"VSS_AT52"
$PN"AT52"10;
"VSS_AT50"
$PN"AT50"10;
"VSS_AT48"
$PN"AT48"10;
"VSS_AT46"
$PN"AT46"10;
"VSS_AT44"
$PN"AT44"10;
"VSS_AT42"
$PN"AT42"10;
"VSS_AT40"
$PN"AT40"10;
"VSS_AT37"
$PN"AT37"10;
"VSS_AT35"
$PN"AT35"10;
"VSS_AT33"
$PN"AT33"10;
"VSS_AT31"
$PN"AT31"10;
"VSS_AT29"
$PN"AT29"10;
"VSS_AT27"
$PN"AT27"10;
"VSS_AT25"
$PN"AT25"10;
"VSS_AT23"
$PN"AT23"10;
"VSS_AT20"
$PN"AT20"10;
"VSS_AT19"
$PN"AT19"10;
"VSS_AT17"
$PN"AT17"10;
"VSS_AT16"
$PN"AT16"10;
"VSS_AT15"
$PN"AT15"10;
"VSS_AT13"
$PN"AT13"10;
"VSS_AT12"
$PN"AT12"10;
"VSS_AT10"
$PN"AT10"10;
"VSS_AT9"
$PN"AT9"10;
"VSS_AT8"
$PN"AT8"9;
"VSS_AT6"
$PN"AT6"9;
"VSS_AT5"
$PN"AT5"9;
"VSS_AT4"
$PN"AT4"9;
"VSS_AT3"
$PN"AT3"9;
"VSS_AR75"
$PN"AR75"9;
"VSS_AR71"
$PN"AR71"9;
"VSS_AR70"
$PN"AR70"9;
"VSS_AR68"
$PN"AR68"9;
"VSS_AR67"
$PN"AR67"9;
"VSS_AR64"
$PN"AR64"9;
"VSS_AR63"
$PN"AR63"9;
"VSS_AR61"
$PN"AR61"9;
"VSS_AR60"
$PN"AR60"9;
"VSS_AR57"
$PN"AR57"9;
"VSS_AR56"
$PN"AR56"9;
"VSS_AR53"
$PN"AR53"9;
"VSS_AR51"
$PN"AR51"9;
"VSS_AR49"
$PN"AR49"9;
"VSS_AR47"
$PN"AR47"9;
"VSS_AR45"
$PN"AR45"9;
"VSS_AR43"
$PN"AR43"9;
"VSS_AR41"
$PN"AR41"9;
"VSS_AR36"
$PN"AR36"9;
"VSS_AR34"
$PN"AR34"9;
"VSS_AR32"
$PN"AR32"9;
"VSS_AR30"
$PN"AR30"9;
"VSS_AR28"
$PN"AR28"9;
"VSS_AR26"
$PN"AR26"9;
"VSS_AR24"
$PN"AR24"9;
"VSS_AR22"
$PN"AR22"9;
"VSS_AR20"
$PN"AR20"9;
"VSS_AR19"
$PN"AR19"9;
"VSS_AR16"
$PN"AR16"9;
"VSS_AR15"
$PN"AR15"9;
"VSS_AR13"
$PN"AR13"9;
"VSS_AR12"
$PN"AR12"9;
"VSS_AR9"
$PN"AR9"9;
"VSS_AR8"
$PN"AR8"9;
"VSS_AR6"
$PN"AR6"9;
"VSS_AR5"
$PN"AR5"9;
"VSS_AR1"
$PN"AR1"9;
"VSS_AP73"
$PN"AP73"9;
"VSS_AP71"
$PN"AP71"9;
"VSS_AP68"
$PN"AP68"9;
"VSS_AP66"
$PN"AP66"9;
"VSS_AP64"
$PN"AP64"9;
"VSS_AP61"
$PN"AP61"9;
"VSS_AP59"
$PN"AP59"9;
"VSS_AP57"
$PN"AP57"9;
"VSS_AP54"
$PN"AP54"9;
"VSS_AP51"
$PN"AP51"9;
"VSS_AP48"
$PN"AP48"9;
"VSS_AP45"
$PN"AP45"9;
"VSS_AP42"
$PN"AP42"9;
"VSS_AP39"
$PN"AP39"9;
"VSS_AP37"
$PN"AP37"9;
"VSS_AP34"
$PN"AP34"9;
"VSS_AP31"
$PN"AP31"9;
"VSS_AP28"
$PN"AP28"9;
"VSS_AP25"
$PN"AP25"9;
"VSS_AP22"
$PN"AP22"9;
"VSS_AP19"
$PN"AP19"9;
"VSS_AP17"
$PN"AP17"9;
"VSS_AP15"
$PN"AP15"9;
"VSS_AP12"
$PN"AP12"9;
"VSS_AP10"
$PN"AP10"9;
"VSS_AP8"
$PN"AP8"9;
"VSS_AP5"
$PN"AP5"9;
"VSS_AP3"
$PN"AP3"9;
"VSS_AN75"
$PN"AN75"9;
"VSS_AN72"
$PN"AN72"9;
"VSS_AN70"
$PN"AN70"9;
"VSS_AN68"
$PN"AN68"9;
"VSS_AN65"
$PN"AN65"9;
"VSS_AN63"
$PN"AN63"9;
"VSS_AN61"
$PN"AN61"9;
"VSS_AN58"
$PN"AN58"9;
"VSS_AN56"
$PN"AN56"9;
"VSS_AN54"
$PN"AN54"9;
"VSS_AN51"
$PN"AN51"9;
"VSS_AN48"
$PN"AN48"9;
"VSS_AN45"
$PN"AN45"9;
"VSS_AN42"
$PN"AN42"9;
"VSS_AN41"
$PN"AN41"9;
"VSS_AN40"
$PN"AN40"9;
"VSS_AN36"
$PN"AN36"9;
"VSS_AN35"
$PN"AN35"9;
"VSS_AN34"
$PN"AN34"9;
"VSS_AN31"
$PN"AN31"9;
"VSS_AN28"
$PN"AN28"9;
"VSS_AN25"
$PN"AN25"9;
"VSS_AN22"
$PN"AN22"9;
"VSS_AN18"
$PN"AN18"9;
"VSS_AN15"
$PN"AN15"9;
"VSS_AN13"
$PN"AN13"9;
"VSS_AN11"
$PN"AN11"9;
"VSS_AN8"
$PN"AN8"9;
"VSS_AN6"
$PN"AN6"9;
"VSS_AN4"
$PN"AN4"9;
"VSS_AN1"
$PN"AN1"9;
"VSS_AM73"
$PN"AM73"9;
"VSS_AM68"
$PN"AM68"9;
"VSS_AM66"
$PN"AM66"9;
"VSS_AM61"
$PN"AM61"9;
"VSS_AM59"
$PN"AM59"9;
"VSS_AM53"
$PN"AM53"9;
"VSS_AM52"
$PN"AM52"9;
"VSS_AM51"
$PN"AM51"9;
"VSS_AM50"
$PN"AM50"9;
"VSS_AM49"
$PN"AM49"9;
"VSS_AM48"
$PN"AM48"9;
"VSS_AM47"
$PN"AM47"9;
"VSS_AM46"
$PN"AM46"9;
"VSS_AM45"
$PN"AM45"9;
"VSS_AM44"
$PN"AM44"9;
"VSS_AM43"
$PN"AM43"9;
"VSS_AM42"
$PN"AM42"9;
%"GENOA_SP5"
"31","(-4075,3500)","0","pure_quanta","I9";
;
LOCATION"U26"
$SEC"31"
CDS_SEC"31"
PART_TYPE"SMLF"
MATERIAL"IO"
VALUE"SOCKET6096_13568-001"
PART_NUMBER"DGA^6000030"
CDS_LIB"pure_quanta"
CDS_LMAN_SYM_OUTLINE"-400,3050,400,-3050"
NEEDS_NO_SIZE"TRUE";
"VSS_AK8"
$PN"AK8"8;
"VSS_AK5"
$PN"AK5"8;
"VSS_AK3"
$PN"AK3"8;
"VSS_AJ75"
$PN"AJ75"8;
"VSS_AJ70"
$PN"AJ70"8;
"VSS_AJ68"
$PN"AJ68"8;
"VSS_AJ63"
$PN"AJ63"8;
"VSS_AJ61"
$PN"AJ61"8;
"VSS_AJ56"
$PN"AJ56"8;
"VSS_AJ54"
$PN"AJ54"8;
"VSS_AJ51"
$PN"AJ51"8;
"VSS_AJ48"
$PN"AJ48"8;
"VSS_AJ45"
$PN"AJ45"8;
"VSS_AJ42"
$PN"AJ42"8;
"VSS_AJ41"
$PN"AJ41"8;
"VSS_AJ40"
$PN"AJ40"8;
"VSS_AJ36"
$PN"AJ36"8;
"VSS_AJ35"
$PN"AJ35"8;
"VSS_AJ34"
$PN"AJ34"8;
"VSS_AJ31"
$PN"AJ31"8;
"VSS_AJ28"
$PN"AJ28"8;
"VSS_AJ25"
$PN"AJ25"8;
"VSS_AJ22"
$PN"AJ22"8;
"VSS_AJ20"
$PN"AJ20"8;
"VSS_AJ15"
$PN"AJ15"8;
"VSS_AJ8"
$PN"AJ8"8;
"VSS_AJ6"
$PN"AJ6"8;
"VSS_AJ1"
$PN"AJ1"8;
"VSS_AH73"
$PN"AH73"8;
"VSS_AH71"
$PN"AH71"8;
"VSS_AH68"
$PN"AH68"8;
"VSS_AH66"
$PN"AH66"8;
"VSS_AH64"
$PN"AH64"8;
"VSS_AH61"
$PN"AH61"8;
"VSS_AH59"
$PN"AH59"8;
"VSS_AH57"
$PN"AH57"8;
"VSS_AH53"
$PN"AH53"8;
"VSS_AH52"
$PN"AH52"8;
"VSS_AH51"
$PN"AH51"8;
"VSS_AH50"
$PN"AH50"8;
"VSS_AH49"
$PN"AH49"8;
"VSS_AH48"
$PN"AH48"8;
"VSS_AH47"
$PN"AH47"8;
"VSS_AH46"
$PN"AH46"8;
"VSS_AH45"
$PN"AH45"8;
"VSS_AH44"
$PN"AH44"8;
"VSS_AH43"
$PN"AH43"7;
"VSS_AH42"
$PN"AH42"7;
"VSS_AH39"
$PN"AH39"7;
"VSS_AH37"
$PN"AH37"7;
"VSS_AH34"
$PN"AH34"7;
"VSS_AH32"
$PN"AH32"7;
"VSS_AH31"
$PN"AH31"7;
"VSS_AH30"
$PN"AH30"7;
"VSS_AH29"
$PN"AH29"7;
"VSS_AH28"
$PN"AH28"7;
"VSS_AH27"
$PN"AH27"7;
"VSS_AH26"
$PN"AH26"7;
"VSS_AH25"
$PN"AH25"7;
"VSS_AH24"
$PN"AH24"7;
"VSS_AH23"
$PN"AH23"7;
"VSS_AH19"
$PN"AH19"7;
"VSS_AH17"
$PN"AH17"7;
"VSS_AH15"
$PN"AH15"7;
"VSS_AH12"
$PN"AH12"7;
"VSS_AH10"
$PN"AH10"7;
"VSS_AH8"
$PN"AH8"7;
"VSS_AH5"
$PN"AH5"7;
"VSS_AH3"
$PN"AH3"7;
"VSS_AG75"
$PN"AG75"7;
"VSS_AG72"
$PN"AG72"7;
"VSS_AG70"
$PN"AG70"7;
"VSS_AG68"
$PN"AG68"7;
"VSS_AG65"
$PN"AG65"7;
"VSS_AG63"
$PN"AG63"7;
"VSS_AG61"
$PN"AG61"7;
"VSS_AG58"
$PN"AG58"7;
"VSS_AG56"
$PN"AG56"7;
"VSS_AG54"
$PN"AG54"7;
"VSS_AG51"
$PN"AG51"7;
"VSS_AG48"
$PN"AG48"7;
"VSS_AG45"
$PN"AG45"7;
"VSS_AG42"
$PN"AG42"7;
"VSS_AG34"
$PN"AG34"7;
"VSS_AG31"
$PN"AG31"7;
"VSS_AG28"
$PN"AG28"7;
"VSS_AG25"
$PN"AG25"7;
"VSS_AG22"
$PN"AG22"7;
"VSS_AG20"
$PN"AG20"7;
"VSS_AG18"
$PN"AG18"7;
"VSS_AG15"
$PN"AG15"7;
"VSS_AG13"
$PN"AG13"7;
"VSS_AG11"
$PN"AG11"7;
"VSS_AG8"
$PN"AG8"7;
"VSS_AG6"
$PN"AG6"7;
"VSS_AG4"
$PN"AG4"7;
"VSS_AG1"
$PN"AG1"7;
"VSS_AF73"
$PN"AF73"7;
"VSS_AF68"
$PN"AF68"7;
"VSS_AF66"
$PN"AF66"7;
"VSS_AF61"
$PN"AF61"7;
"VSS_AF59"
$PN"AF59"7;
"VSS_AF54"
$PN"AF54"7;
"VSS_AF51"
$PN"AF51"7;
"VSS_AF48"
$PN"AF48"7;
"VSS_AF45"
$PN"AF45"7;
"VSS_AF42"
$PN"AF42"7;
"VSS_AF39"
$PN"AF39"7;
"VSS_AF37"
$PN"AF37"7;
"VSS_AF34"
$PN"AF34"7;
"VSS_AF31"
$PN"AF31"7;
"VSS_AF28"
$PN"AF28"7;
"VSS_AF25"
$PN"AF25"7;
"VSS_AF22"
$PN"AF22"7;
"VSS_AF17"
$PN"AF17"7;
"VSS_AF15"
$PN"AF15"7;
"VSS_AF10"
$PN"AF10"7;
"VSS_AF8"
$PN"AF8"7;
"VSS_AF3"
$PN"AF3"7;
"VSS_AE75"
$PN"AE75"7;
"VSS_AE72"
$PN"AE72"7;
"VSS_AE70"
$PN"AE70"7;
"VSS_AE68"
$PN"AE68"7;
"VSS_AE65"
$PN"AE65"7;
"VSS_AE63"
$PN"AE63"7;
"VSS_AE61"
$PN"AE61"7;
"VSS_AE58"
$PN"AE58"7;
"VSS_AE56"
$PN"AE56"7;
"VSS_AE54"
$PN"AE54"7;
"VSS_AE51"
$PN"AE51"7;
"VSS_AE48"
$PN"AE48"7;
"VSS_AE45"
$PN"AE45"7;
"VSS_AE42"
$PN"AE42"7;
"VSS_AE41"
$PN"AE41"7;
"VSS_AE40"
$PN"AE40"7;
"VSS_AE36"
$PN"AE36"7;
"VSS_AE35"
$PN"AE35"7;
"VSS_AE34"
$PN"AE34"7;
"VSS_AE31"
$PN"AE31"7;
"VSS_AE28"
$PN"AE28"7;
"VSS_AE25"
$PN"AE25"7;
"VSS_AE22"
$PN"AE22"7;
"VSS_AE20"
$PN"AE20"7;
"VSS_AE18"
$PN"AE18"7;
"VSS_AE15"
$PN"AE15"7;
"VSS_AE13"
$PN"AE13"7;
"VSS_AE11"
$PN"AE11"7;
"VSS_AE8"
$PN"AE8"7;
"VSS_AE6"
$PN"AE6"7;
"VSS_AE1"
$PN"AE1"7;
"VSS_AD73"
$PN"AD73"7;
"VSS_AD71"
$PN"AD71"7;
"VSS_AD68"
$PN"AD68"7;
"VSS_AD66"
$PN"AD66"7;
"VSS_AD64"
$PN"AD64"7;
"VSS_AD61"
$PN"AD61"7;
"VSS_AD59"
$PN"AD59"7;
"VSS_AD57"
$PN"AD57"7;
"VSS_AD53"
$PN"AD53"7;
"VSS_AD52"
$PN"AD52"7;
"VSS_AD51"
$PN"AD51"7;
"VSS_AD50"
$PN"AD50"7;
"VSS_AD49"
$PN"AD49"7;
"VSS_AM39"
$PN"AM39"8;
"VSS_AM34"
$PN"AM34"8;
"VSS_AM33"
$PN"AM33"8;
"VSS_AM32"
$PN"AM32"8;
"VSS_AM31"
$PN"AM31"8;
"VSS_AM30"
$PN"AM30"8;
"VSS_AM29"
$PN"AM29"8;
"VSS_AM28"
$PN"AM28"8;
"VSS_AM27"
$PN"AM27"8;
"VSS_AM26"
$PN"AM26"8;
"VSS_AM25"
$PN"AM25"8;
"VSS_AM24"
$PN"AM24"8;
"VSS_AM23"
$PN"AM23"8;
"VSS_AM17"
$PN"AM17"8;
"VSS_AM15"
$PN"AM15"8;
"VSS_AM10"
$PN"AM10"8;
"VSS_AM8"
$PN"AM8"8;
"VSS_AM3"
$PN"AM3"8;
"VSS_AL75"
$PN"AL75"8;
"VSS_AL72"
$PN"AL72"8;
"VSS_AL70"
$PN"AL70"8;
"VSS_AL68"
$PN"AL68"8;
"VSS_AL65"
$PN"AL65"8;
"VSS_AL63"
$PN"AL63"8;
"VSS_AL61"
$PN"AL61"8;
"VSS_AL58"
$PN"AL58"8;
"VSS_AL56"
$PN"AL56"8;
"VSS_AL54"
$PN"AL54"8;
"VSS_AL51"
$PN"AL51"8;
"VSS_AL48"
$PN"AL48"8;
"VSS_AL45"
$PN"AL45"8;
"VSS_AL42"
$PN"AL42"8;
"VSS_AL34"
$PN"AL34"8;
"VSS_AL31"
$PN"AL31"8;
"VSS_AL28"
$PN"AL28"8;
"VSS_AL25"
$PN"AL25"8;
"VSS_AL22"
$PN"AL22"8;
"VSS_AL20"
$PN"AL20"8;
"VSS_AL18"
$PN"AL18"8;
"VSS_AL15"
$PN"AL15"8;
"VSS_AL13"
$PN"AL13"8;
"VSS_AL11"
$PN"AL11"8;
"VSS_AL8"
$PN"AL8"8;
"VSS_AL6"
$PN"AL6"8;
"VSS_AL4"
$PN"AL4"8;
"VSS_AL1"
$PN"AL1"8;
"VSS_AK73"
$PN"AK73"8;
"VSS_AK71"
$PN"AK71"8;
"VSS_AK68"
$PN"AK68"8;
"VSS_AK66"
$PN"AK66"8;
"VSS_AK64"
$PN"AK64"8;
"VSS_AK61"
$PN"AK61"8;
"VSS_AK59"
$PN"AK59"8;
"VSS_AK57"
$PN"AK57"8;
"VSS_AK54"
$PN"AK54"8;
"VSS_AK51"
$PN"AK51"8;
"VSS_AK48"
$PN"AK48"8;
"VSS_AK45"
$PN"AK45"8;
"VSS_AK42"
$PN"AK42"8;
"VSS_AK39"
$PN"AK39"8;
"VSS_AK37"
$PN"AK37"8;
"VSS_AK34"
$PN"AK34"8;
"VSS_AK31"
$PN"AK31"8;
"VSS_AK28"
$PN"AK28"8;
"VSS_AK25"
$PN"AK25"8;
"VSS_AK22"
$PN"AK22"8;
"VSS_AK19"
$PN"AK19"8;
"VSS_AK17"
$PN"AK17"8;
"VSS_AK15"
$PN"AK15"8;
"VSS_AK12"
$PN"AK12"8;
"VSS_AK10"
$PN"AK10"8;
END.
